# S9S_MB_2U (Grand Teton) — schematic netlist excerpt (pin names and nets, part order shuffled) for the footprints in the layout excerpt that follows; sources: Cadence DE-HDL packaged netlist, KiCad conversion of 03242023_DA0F0TMBIJ0_F0T_Motherboard_J_brd_V01_OCP.brd

R840  Q_RES  1K 1% CHIP  pkg 0402LF  page 129 : A = PVCCD_HV_CPU0 ; B = RST_M_AB_CPU0_FPGA_N
C117  Q_CAP  0.047UF 25V 10% X7R  pkg C0402  page 210 : A = P3V3_AUX_CLK_GEN_VDDMXCK_CK440 ; B = GND

(kicad_pcb
	(version 20260206)
	(generator "pcbnew")
	(generator_version "10.0")
	(general
		(thickness 1.6)
		(legacy_teardrops no)
	)
	(paper "A4")
	(title_block
		(title "03242023_DA0F0TMBIJ0_F0T_Motherboard_J_brd_V01_OCP.brd")
		(comment 1 "Grand Teton / footprints 5288-5289 of 6105")
	)
	(layers
		(0 "F.Cu" signal "TOP")
		(4 "In1.Cu" signal "GND")
		(6 "In2.Cu" signal "IN1")
		(8 "In3.Cu" signal "GND1")
		(10 "In4.Cu" signal "IN2")
		(12 "In5.Cu" signal "GND2")
		(14 "In6.Cu" signal "IN3")
		(16 "In7.Cu" signal "GND3")
		(18 "In8.Cu" signal "VCC")
		(20 "In9.Cu" signal "VCC1")
		(22 "In10.Cu" signal "GND4")
		(24 "In11.Cu" signal "IN4")
		(26 "In12.Cu" signal "GND5")
		(28 "In13.Cu" signal "IN5")
		(30 "In14.Cu" signal "GND6")
		(32 "In15.Cu" signal "IN6")
		(34 "In16.Cu" signal "GND7")
		(2 "B.Cu" signal "BOTTOM")
		(9 "F.Adhes" user "F.Adhesive")
		(11 "B.Adhes" user "B.Adhesive")
		(13 "F.Paste" user "Package Geometry/Pastemask Top")
		(15 "B.Paste" user "Package Geometry/Pastemask Bottom")
		(5 "F.SilkS" user "Ref Des/Silkscreen Top")
		(7 "B.SilkS" user "Ref Des/Silkscreen Bottom")
		(1 "F.Mask" user "Board Geometry/Soldermask Top")
		(3 "B.Mask" user "Board Geometry/Soldermask Bottom")
		(17 "Dwgs.User" user "User.Drawings")
		(19 "Cmts.User" user "User.Comments")
		(21 "Eco1.User" user "User.Eco1")
		(23 "Eco2.User" user "User.Eco2")
		(25 "Edge.Cuts" user "Board Geometry/Outline")
		(27 "Margin" user)
		(31 "F.CrtYd" user "Package Geometry/Place Bound Top")
		(29 "B.CrtYd" user "Package Geometry/Place Bound Bottom")
		(35 "F.Fab" user "Ref Des/Assembly Top")
		(33 "B.Fab" user "Ref Des/Assembly Bottom")
	)
	(footprint ""
		(layer "B.Cu")
		(at 286.478726 -193.691256 -90)
		(property "Reference" "R840"
			(at 0 0 90)
			(layer "B.SilkS")
			(hide yes)
			(effects
				(font
					(size 1.27 1.27)
				)
				(justify mirror)
			)
		)
		(property "Value" ""
			(at 0 0 90)
			(layer "B.Fab")
			(effects
				(font
					(size 1.27 1.27)
				)
				(justify mirror)
			)
		)
		(duplicate_pad_numbers_are_jumpers no)
		(fp_line
			(start -0.7874 0.4064)
			(end 0.7874 0.4064)
			(stroke
				(width 0.1524)
				(type default)
			)
			(layer "B.SilkS")
		)
		(fp_line
			(start 0.7874 0.4064)
			(end 0.7874 -0.4064)
			(stroke
				(width 0.1524)
				(type default)
			)
			(layer "B.SilkS")
		)
		(fp_line
			(start -0.7874 -0.4064)
			(end -0.7874 0.4064)
			(stroke
				(width 0.1524)
				(type default)
			)
			(layer "B.SilkS")
		)
		(fp_line
			(start 0.7874 -0.4064)
			(end -0.7874 -0.4064)
			(stroke
				(width 0.1524)
				(type default)
			)
			(layer "B.SilkS")
		)
		(fp_line
			(start -0.67945 0.3048)
			(end -0.120396 0.3048)
			(stroke
				(width 0.1)
				(type default)
			)
			(layer "B.Fab")
		)
		(fp_line
			(start -0.120396 0.3048)
			(end -0.120396 0.2794)
			(stroke
				(width 0.1)
				(type default)
			)
			(layer "B.Fab")
		)
		(fp_line
			(start 0.12065 0.3048)
			(end 0.67945 0.3048)
			(stroke
				(width 0.1)
				(type default)
			)
			(layer "B.Fab")
		)
		(fp_line
			(start 0.67945 0.3048)
			(end 0.67945 -0.305054)
			(stroke
				(width 0.1)
				(type default)
			)
			(layer "B.Fab")
		)
		(fp_line
			(start -0.120396 0.2794)
			(end 0.12065 0.2794)
			(stroke
				(width 0.1)
				(type default)
			)
			(layer "B.Fab")
		)
		(fp_line
			(start 0.12065 0.2794)
			(end 0.12065 0.3048)
			(stroke
				(width 0.1)
				(type default)
			)
			(layer "B.Fab")
		)
		(fp_line
			(start -0.12065 -0.2794)
			(end -0.12065 -0.3048)
			(stroke
				(width 0.1)
				(type default)
			)
			(layer "B.Fab")
		)
		(fp_line
			(start 0.12065 -0.2794)
			(end -0.12065 -0.2794)
			(stroke
				(width 0.1)
				(type default)
			)
			(layer "B.Fab")
		)
		(fp_line
			(start -0.67945 -0.3048)
			(end -0.67945 0.3048)
			(stroke
				(width 0.1)
				(type default)
			)
			(layer "B.Fab")
		)
		(fp_line
			(start -0.12065 -0.3048)
			(end -0.67945 -0.3048)
			(stroke
				(width 0.1)
				(type default)
			)
			(layer "B.Fab")
		)
		(fp_line
			(start 0.12065 -0.305054)
			(end 0.12065 -0.2794)
			(stroke
				(width 0.1)
				(type default)
			)
			(layer "B.Fab")
		)
		(fp_line
			(start 0.67945 -0.305054)
			(end 0.12065 -0.305054)
			(stroke
				(width 0.1)
				(type default)
			)
			(layer "B.Fab")
		)
		(pad "1" smd circle
			(at 0.40005 0 90)
			(size 0 0)
			(layers "B.Cu" "B.Mask" "B.Paste")
			(net "PVCCD_HV_CPU0")
		)
		(pad "2" smd circle
			(at -0.40005 0 90)
			(size 0 0)
			(layers "B.Cu" "B.Mask" "B.Paste")
			(net "RST_M_AB_CPU0_FPGA_N")
		)
	)
	(footprint ""
		(layer "B.Cu")
		(at 256.370836 -102.277418 90)
		(property "Reference" "C117"
			(at 0 0 90)
			(layer "B.SilkS")
			(hide yes)
			(effects
				(font
					(size 1.27 1.27)
				)
				(justify mirror)
			)
		)
		(property "Value" ""
			(at 0 0 90)
			(layer "B.Fab")
			(effects
				(font
					(size 1.27 1.27)
				)
				(justify mirror)
			)
		)
		(duplicate_pad_numbers_are_jumpers no)
		(fp_line
			(start 0.7874 -0.4064)
			(end -0.7874 -0.4064)
			(stroke
				(width 0.1524)
				(type default)
			)
			(layer "B.SilkS")
		)
		(fp_line
			(start -0.7874 -0.4064)
			(end -0.7874 0.4064)
			(stroke
				(width 0.1524)
				(type default)
			)
			(layer "B.SilkS")
		)
		(fp_line
			(start 0.7874 0.4064)
			(end 0.7874 -0.4064)
			(stroke
				(width 0.1524)
				(type default)
			)
			(layer "B.SilkS")
		)
		(fp_line
			(start -0.7874 0.4064)
			(end 0.7874 0.4064)
			(stroke
				(width 0.1524)
				(type default)
			)
			(layer "B.SilkS")
		)
		(fp_line
			(start 0.67945 -0.305054)
			(end 0.12065 -0.305054)
			(stroke
				(width 0.1)
				(type default)
			)
			(layer "B.Fab")
		)
		(fp_line
			(start 0.12065 -0.305054)
			(end 0.12065 -0.2794)
			(stroke
				(width 0.1)
				(type default)
			)
			(layer "B.Fab")
		)
		(fp_line
			(start -0.12065 -0.3048)
			(end -0.67945 -0.3048)
			(stroke
				(width 0.1)
				(type default)
			)
			(layer "B.Fab")
		)
		(fp_line
			(start -0.67945 -0.3048)
			(end -0.67945 0.3048)
			(stroke
				(width 0.1)
				(type default)
			)
			(layer "B.Fab")
		)
		(fp_line
			(start 0.12065 -0.2794)
			(end -0.12065 -0.2794)
			(stroke
				(width 0.1)
				(type default)
			)
			(layer "B.Fab")
		)
		(fp_line
			(start -0.12065 -0.2794)
			(end -0.12065 -0.3048)
			(stroke
				(width 0.1)
				(type default)
			)
			(layer "B.Fab")
		)
		(fp_line
			(start 0.12065 0.2794)
			(end 0.12065 0.3048)
			(stroke
				(width 0.1)
				(type default)
			)
			(layer "B.Fab")
		)
		(fp_line
			(start -0.120396 0.2794)
			(end 0.12065 0.2794)
			(stroke
				(width 0.1)
				(type default)
			)
			(layer "B.Fab")
		)
		(fp_line
			(start 0.67945 0.3048)
			(end 0.67945 -0.305054)
			(stroke
				(width 0.1)
				(type default)
			)
			(layer "B.Fab")
		)
		(fp_line
			(start 0.12065 0.3048)
			(end 0.67945 0.3048)
			(stroke
				(width 0.1)
				(type default)
			)
			(layer "B.Fab")
		)
		(fp_line
			(start -0.120396 0.3048)
			(end -0.120396 0.2794)
			(stroke
				(width 0.1)
				(type default)
			)
			(layer "B.Fab")
		)
		(fp_line
			(start -0.67945 0.3048)
			(end -0.120396 0.3048)
			(stroke
				(width 0.1)
				(type default)
			)
			(layer "B.Fab")
		)
		(pad "1" smd circle
			(at 0.40005 0 270)
			(size 0 0)
			(layers "B.Cu" "B.Mask" "B.Paste")
			(net "P3V3_AUX_CLK_GEN_VDDMXCK_CK440")
		)
		(pad "2" smd circle
			(at -0.40005 0 270)
			(size 0 0)
			(layers "B.Cu" "B.Mask" "B.Paste")
			(net "GND")
		)
	)
)
